(kicad_pcb
	(version 20260206)
	(generator "pcbnew")
	(generator_version "10.0")
	(general
		(thickness 1.6)
		(legacy_teardrops no)
	)
	(paper "A4")
	(title_block
		(title "01162023_DA0F0TEBIF0_F0T_Expander_BD_F_brd_V02_OCP.brd")
		(comment 1 "Grand Teton / footprints 737-741 of 9728")
	)
	(layers
		(0 "F.Cu" signal "TOP")
		(4 "In1.Cu" signal "GND")
		(6 "In2.Cu" signal "VCC")
		(8 "In3.Cu" signal "VCC1")
		(10 "In4.Cu" signal "GND1")
		(12 "In5.Cu" signal "IN1")
		(14 "In6.Cu" signal "GND2")
		(16 "In7.Cu" signal "IN2")
		(18 "In8.Cu" signal "GND3")
		(20 "In9.Cu" signal "IN3")
		(22 "In10.Cu" signal "GND4")
		(24 "In11.Cu" signal "IN4")
		(26 "In12.Cu" signal "GND5")
		(28 "In13.Cu" signal "IN5")
		(30 "In14.Cu" signal "GND6")
		(32 "In15.Cu" signal "IN6")
		(34 "In16.Cu" signal "GND7")
		(2 "B.Cu" signal "BOTTOM")
		(9 "F.Adhes" user "F.Adhesive")
		(11 "B.Adhes" user "B.Adhesive")
		(13 "F.Paste" user "Package Geometry/Pastemask Top")
		(15 "B.Paste" user "Package Geometry/Pastemask Bottom")
		(5 "F.SilkS" user "Ref Des/Silkscreen Top")
		(7 "B.SilkS" user "Ref Des/Silkscreen Bottom")
		(1 "F.Mask" user "Board Geometry/Soldermask Top")
		(3 "B.Mask" user "Board Geometry/Soldermask Bottom")
		(17 "Dwgs.User" user "User.Drawings")
		(19 "Cmts.User" user "User.Comments")
		(21 "Eco1.User" user "User.Eco1")
		(23 "Eco2.User" user "User.Eco2")
		(25 "Edge.Cuts" user "Board Geometry/Outline")
		(27 "Margin" user)
		(31 "F.CrtYd" user "Package Geometry/Place Bound Top")
		(29 "B.CrtYd" user "Package Geometry/Place Bound Bottom")
		(35 "F.Fab" user "Ref Des/Assembly Top")
		(33 "B.Fab" user "Ref Des/Assembly Bottom")
	)
	(footprint ""
		(layer "F.Cu")
		(at 447.275712 -118.467886)
		(property "Reference" "PC495"
			(at 0 0 0)
			(layer "F.SilkS")
			(hide yes)
			(effects
				(font
					(size 1.27 1.27)
				)
			)
		)
		(property "Value" ""
			(at 0 0 0)
			(layer "F.Fab")
			(effects
				(font
					(size 1.27 1.27)
				)
			)
		)
		(duplicate_pad_numbers_are_jumpers no)
		(fp_line
			(start -0.7874 -0.4064)
			(end 0.7874 -0.4064)
			(stroke
				(width 0.1524)
				(type default)
			)
			(layer "F.SilkS")
		)
		(fp_line
			(start -0.7874 0.4064)
			(end -0.7874 -0.4064)
			(stroke
				(width 0.1524)
				(type default)
			)
			(layer "F.SilkS")
		)
		(fp_line
			(start 0.7874 -0.4064)
			(end 0.7874 0.4064)
			(stroke
				(width 0.1524)
				(type default)
			)
			(layer "F.SilkS")
		)
		(fp_line
			(start 0.7874 0.4064)
			(end -0.7874 0.4064)
			(stroke
				(width 0.1524)
				(type default)
			)
			(layer "F.SilkS")
		)
		(fp_line
			(start -0.67945 -0.305054)
			(end -0.12065 -0.305054)
			(stroke
				(width 0.1)
				(type default)
			)
			(layer "F.Fab")
		)
		(fp_line
			(start -0.67945 0.3048)
			(end -0.67945 -0.305054)
			(stroke
				(width 0.1)
				(type default)
			)
			(layer "F.Fab")
		)
		(fp_line
			(start -0.12065 -0.305054)
			(end -0.12065 -0.2794)
			(stroke
				(width 0.1)
				(type default)
			)
			(layer "F.Fab")
		)
		(fp_line
			(start -0.12065 -0.2794)
			(end 0.12065 -0.2794)
			(stroke
				(width 0.1)
				(type default)
			)
			(layer "F.Fab")
		)
		(fp_line
			(start -0.12065 0.2794)
			(end -0.12065 0.3048)
			(stroke
				(width 0.1)
				(type default)
			)
			(layer "F.Fab")
		)
		(fp_line
			(start -0.12065 0.3048)
			(end -0.67945 0.3048)
			(stroke
				(width 0.1)
				(type default)
			)
			(layer "F.Fab")
		)
		(fp_line
			(start 0.120396 0.2794)
			(end -0.12065 0.2794)
			(stroke
				(width 0.1)
				(type default)
			)
			(layer "F.Fab")
		)
		(fp_line
			(start 0.120396 0.3048)
			(end 0.120396 0.2794)
			(stroke
				(width 0.1)
				(type default)
			)
			(layer "F.Fab")
		)
		(fp_line
			(start 0.12065 -0.3048)
			(end 0.67945 -0.3048)
			(stroke
				(width 0.1)
				(type default)
			)
			(layer "F.Fab")
		)
		(fp_line
			(start 0.12065 -0.2794)
			(end 0.12065 -0.3048)
			(stroke
				(width 0.1)
				(type default)
			)
			(layer "F.Fab")
		)
		(fp_line
			(start 0.67945 -0.3048)
			(end 0.67945 0.3048)
			(stroke
				(width 0.1)
				(type default)
			)
			(layer "F.Fab")
		)
		(fp_line
			(start 0.67945 0.3048)
			(end 0.120396 0.3048)
			(stroke
				(width 0.1)
				(type default)
			)
			(layer "F.Fab")
		)
		(pad "1" smd circle
			(at -0.40005 0)
			(size 0 0)
			(layers "F.Cu" "F.Mask" "F.Paste")
			(net "P3V3_NIC7_SS")
		)
		(pad "2" smd circle
			(at 0.40005 0)
			(size 0 0)
			(layers "F.Cu" "F.Mask" "F.Paste")
			(net "GND")
		)
	)
	(footprint ""
		(layer "F.Cu")
		(at 138.946128 -46.4439 180)
		(property "Reference" "U59"
			(at -0.042672 -2.40157 0)
			(unlocked yes)
			(layer "F.SilkS")
			(effects
				(font
					(size 0.7874 0.5842)
					(thickness 0.1524)
				)
			)
		)
		(property "Value" ""
			(at 0 0 180)
			(layer "F.Fab")
			(effects
				(font
					(size 1.27 1.27)
				)
			)
		)
		(duplicate_pad_numbers_are_jumpers no)
		(fp_line
			(start 1.500124 1.500124)
			(end 1.004062 1.500124)
			(stroke
				(width 0.1524)
				(type default)
			)
			(layer "F.SilkS")
		)
		(fp_line
			(start 1.500124 1.004062)
			(end 1.500124 1.500124)
			(stroke
				(width 0.1524)
				(type default)
			)
			(layer "F.SilkS")
		)
		(fp_line
			(start 1.500124 -1.500124)
			(end 1.500124 -1.004062)
			(stroke
				(width 0.1524)
				(type default)
			)
			(layer "F.SilkS")
		)
		(fp_line
			(start 1.004062 -1.500124)
			(end 1.500124 -1.500124)
			(stroke
				(width 0.1524)
				(type default)
			)
			(layer "F.SilkS")
		)
		(fp_line
			(start -1.004062 1.500124)
			(end -1.500124 1.500124)
			(stroke
				(width 0.1524)
				(type default)
			)
			(layer "F.SilkS")
		)
		(fp_line
			(start -1.500124 1.500124)
			(end -1.500124 1.004062)
			(stroke
				(width 0.1524)
				(type default)
			)
			(layer "F.SilkS")
		)
		(fp_line
			(start -1.500124 -1.004062)
			(end -1.500124 -1.500124)
			(stroke
				(width 0.1524)
				(type default)
			)
			(layer "F.SilkS")
		)
		(fp_line
			(start -1.500124 -1.500124)
			(end -1.004062 -1.500124)
			(stroke
				(width 0.1524)
				(type default)
			)
			(layer "F.SilkS")
		)
		(fp_poly
			(pts
				(xy -1.957832 -1.995678) (xy -2.676144 -1.277366) (xy -1.598422 -0.917956)
			)
			(stroke
				(width 0)
				(type default)
			)
			(fill yes)
			(layer "F.SilkS")
		)
		(fp_line
			(start 1.500124 1.500124)
			(end -1.500124 1.500124)
			(stroke
				(width 0.1)
				(type default)
			)
			(layer "F.Fab")
		)
		(fp_line
			(start 1.500124 -1.500124)
			(end 1.500124 1.500124)
			(stroke
				(width 0.1)
				(type default)
			)
			(layer "F.Fab")
		)
		(fp_line
			(start -1.500124 1.500124)
			(end -1.500124 -1.500124)
			(stroke
				(width 0.1)
				(type default)
			)
			(layer "F.Fab")
		)
		(fp_line
			(start -1.500124 -1.500124)
			(end 1.500124 -1.500124)
			(stroke
				(width 0.1)
				(type default)
			)
			(layer "F.Fab")
		)
		(fp_poly
			(pts
				(xy -2.847848 -1.258062) (xy -2.847848 -0.242062) (xy -1.831848 -0.750062)
			)
			(stroke
				(width 0)
				(type default)
			)
			(fill yes)
			(layer "F.Fab")
		)
		(pad "1" smd rect
			(at -1.400048 -0.750062 90)
			(size 0.2286 0.6096)
			(layers "F.Cu" "F.Mask" "F.Paste")
			(net "SSD4_ADC_A1")
		)
		(pad "2" smd rect
			(at -1.400048 -0.249936 90)
			(size 0.2286 0.6096)
			(layers "F.Cu" "F.Mask" "F.Paste")
			(net "SSD4_ADC_A0")
		)
		(pad "3" smd rect
			(at -1.400048 0.249936 90)
			(size 0.2286 0.6096)
			(layers "F.Cu" "F.Mask" "F.Paste")
			(net "SSD4_ADC_ALERT_N")
		)
		(pad "4" smd rect
			(at -1.400048 0.750062 90)
			(size 0.2286 0.6096)
			(layers "F.Cu" "F.Mask" "F.Paste")
			(net "SMB_SSD4_ADC_SDA")
		)
		(pad "5" smd rect
			(at -0.750062 1.400048 180)
			(size 0.2286 0.6096)
			(layers "F.Cu" "F.Mask" "F.Paste")
			(net "SMB_SSD4_ADC_SCL")
		)
		(pad "6" smd rect
			(at -0.249936 1.400048 180)
			(size 0.2286 0.6096)
			(layers "F.Cu" "F.Mask" "F.Paste")
			(net "Net_8738")
		)
		(pad "7" smd rect
			(at 0.249936 1.400048 180)
			(size 0.2286 0.6096)
			(layers "F.Cu" "F.Mask" "F.Paste")
			(net "Net_8737")
		)
		(pad "8" smd rect
			(at 0.750062 1.400048 180)
			(size 0.2286 0.6096)
			(layers "F.Cu" "F.Mask" "F.Paste")
			(net "Net_8736")
		)
		(pad "9" smd rect
			(at 1.400048 0.750062 90)
			(size 0.2286 0.6096)
			(layers "F.Cu" "F.Mask" "F.Paste")
			(net "P3V3_AUX")
		)
		(pad "10" smd rect
			(at 1.400048 0.249936 90)
			(size 0.2286 0.6096)
			(layers "F.Cu" "F.Mask" "F.Paste")
			(net "GND")
		)
		(pad "11" smd rect
			(at 1.400048 -0.249936 90)
			(size 0.2286 0.6096)
			(layers "F.Cu" "F.Mask" "F.Paste")
			(net "P12V_SSD4_R")
		)
		(pad "12" smd rect
			(at 1.400048 -0.750062 90)
			(size 0.2286 0.6096)
			(layers "F.Cu" "F.Mask" "F.Paste")
			(net "P12V_SSD4_VIN_N")
		)
		(pad "13" smd rect
			(at 0.750062 -1.400048 180)
			(size 0.2286 0.6096)
			(layers "F.Cu" "F.Mask" "F.Paste")
			(net "P12V_SSD4_VIN_P")
		)
		(pad "14" smd rect
			(at 0.249936 -1.400048 180)
			(size 0.2286 0.6096)
			(layers "F.Cu" "F.Mask" "F.Paste")
			(net "Net_8735")
		)
		(pad "15" smd rect
			(at -0.249936 -1.400048 180)
			(size 0.2286 0.6096)
			(layers "F.Cu" "F.Mask" "F.Paste")
			(net "Net_8734")
		)
		(pad "16" smd rect
			(at -0.750062 -1.400048 180)
			(size 0.2286 0.6096)
			(layers "F.Cu" "F.Mask" "F.Paste")
			(net "Net_8733")
		)
		(pad "TH" smd rect
			(at 0 0 180)
			(size 1.7018 1.7018)
			(layers "F.Cu" "F.Mask" "F.Paste")
			(net "GND")
		)
		(zone
			(layer "F.Cu")
			(hatch none 0.5)
			(connect_pads
				(clearance 0)
			)
			(min_thickness 0.25)
			(keepout
				(tracks not_allowed)
				(vias allowed)
				(pads allowed)
				(copperpour not_allowed)
				(footprints allowed)
			)
			(placement
				(enabled no)
				(sheetname "")
			)
			(fill
				(thermal_gap 0.5)
				(thermal_bridge_width 0.5)
				(island_removal_mode 0)
			)
			(polygon
				(pts
					(xy 139.990576 -46.4185) (xy 139.990576 -45.399452) (xy 137.90168 -45.399452) (xy 137.90168 -47.488348)
					(xy 139.990576 -47.488348) (xy 139.990576 -46.4439) (xy 139.847828 -46.4439) (xy 139.847828 -47.3456)
					(xy 138.044428 -47.3456) (xy 138.044428 -45.5422) (xy 139.847828 -45.5422) (xy 139.847828 -46.4185)
				)
			)
		)
	)
	(footprint ""
		(layer "F.Cu")
		(at 464.381088 -279.535128 -90)
		(property "Reference" "R1771"
			(at 0 0 270)
			(layer "F.SilkS")
			(hide yes)
			(effects
				(font
					(size 1.27 1.27)
				)
			)
		)
		(property "Value" ""
			(at 0 0 270)
			(layer "F.Fab")
			(effects
				(font
					(size 1.27 1.27)
				)
			)
		)
		(duplicate_pad_numbers_are_jumpers no)
		(fp_line
			(start -0.7874 0.4064)
			(end -0.7874 -0.4064)
			(stroke
				(width 0.1524)
				(type default)
			)
			(layer "F.SilkS")
		)
		(fp_line
			(start 0.7874 0.4064)
			(end -0.7874 0.4064)
			(stroke
				(width 0.1524)
				(type default)
			)
			(layer "F.SilkS")
		)
		(fp_line
			(start -0.7874 -0.4064)
			(end 0.7874 -0.4064)
			(stroke
				(width 0.1524)
				(type default)
			)
			(layer "F.SilkS")
		)
		(fp_line
			(start 0.7874 -0.4064)
			(end 0.7874 0.4064)
			(stroke
				(width 0.1524)
				(type default)
			)
			(layer "F.SilkS")
		)
		(fp_line
			(start -0.67945 0.3048)
			(end -0.67945 -0.305054)
			(stroke
				(width 0.1)
				(type default)
			)
			(layer "F.Fab")
		)
		(fp_line
			(start -0.12065 0.3048)
			(end -0.67945 0.3048)
			(stroke
				(width 0.1)
				(type default)
			)
			(layer "F.Fab")
		)
		(fp_line
			(start 0.120396 0.3048)
			(end 0.120396 0.2794)
			(stroke
				(width 0.1)
				(type default)
			)
			(layer "F.Fab")
		)
		(fp_line
			(start 0.67945 0.3048)
			(end 0.120396 0.3048)
			(stroke
				(width 0.1)
				(type default)
			)
			(layer "F.Fab")
		)
		(fp_line
			(start -0.12065 0.2794)
			(end -0.12065 0.3048)
			(stroke
				(width 0.1)
				(type default)
			)
			(layer "F.Fab")
		)
		(fp_line
			(start 0.120396 0.2794)
			(end -0.12065 0.2794)
			(stroke
				(width 0.1)
				(type default)
			)
			(layer "F.Fab")
		)
		(fp_line
			(start -0.12065 -0.2794)
			(end 0.12065 -0.2794)
			(stroke
				(width 0.1)
				(type default)
			)
			(layer "F.Fab")
		)
		(fp_line
			(start 0.12065 -0.2794)
			(end 0.12065 -0.3048)
			(stroke
				(width 0.1)
				(type default)
			)
			(layer "F.Fab")
		)
		(fp_line
			(start 0.12065 -0.3048)
			(end 0.67945 -0.3048)
			(stroke
				(width 0.1)
				(type default)
			)
			(layer "F.Fab")
		)
		(fp_line
			(start 0.67945 -0.3048)
			(end 0.67945 0.3048)
			(stroke
				(width 0.1)
				(type default)
			)
			(layer "F.Fab")
		)
		(fp_line
			(start -0.67945 -0.305054)
			(end -0.12065 -0.305054)
			(stroke
				(width 0.1)
				(type default)
			)
			(layer "F.Fab")
		)
		(fp_line
			(start -0.12065 -0.305054)
			(end -0.12065 -0.2794)
			(stroke
				(width 0.1)
				(type default)
			)
			(layer "F.Fab")
		)
		(pad "1" smd circle
			(at -0.40005 0 270)
			(size 0 0)
			(layers "F.Cu" "F.Mask" "F.Paste")
			(net "SMB_BIC_I2C6_MUX_PEX_ADC_R_SCL")
		)
		(pad "2" smd circle
			(at 0.40005 0 270)
			(size 0 0)
			(layers "F.Cu" "F.Mask" "F.Paste")
			(net "SMB_BIC_I2C6_MUX_PEX_ADC_SCL")
		)
	)
	(footprint ""
		(layer "F.Cu")
		(at 14.788896 -119.140986 90)
		(property "Reference" "PC665"
			(at 0 0 90)
			(layer "F.SilkS")
			(hide yes)
			(effects
				(font
					(size 1.27 1.27)
				)
			)
		)
		(property "Value" ""
			(at 0 0 90)
			(layer "F.Fab")
			(effects
				(font
					(size 1.27 1.27)
				)
			)
		)
		(duplicate_pad_numbers_are_jumpers no)
		(fp_line
			(start 0.7874 -0.4064)
			(end 0.7874 0.4064)
			(stroke
				(width 0.1524)
				(type default)
			)
			(layer "F.SilkS")
		)
		(fp_line
			(start -0.7874 -0.4064)
			(end 0.7874 -0.4064)
			(stroke
				(width 0.1524)
				(type default)
			)
			(layer "F.SilkS")
		)
		(fp_line
			(start 0.7874 0.4064)
			(end -0.7874 0.4064)
			(stroke
				(width 0.1524)
				(type default)
			)
			(layer "F.SilkS")
		)
		(fp_line
			(start -0.7874 0.4064)
			(end -0.7874 -0.4064)
			(stroke
				(width 0.1524)
				(type default)
			)
			(layer "F.SilkS")
		)
		(fp_line
			(start -0.12065 -0.305054)
			(end -0.12065 -0.2794)
			(stroke
				(width 0.1)
				(type default)
			)
			(layer "F.Fab")
		)
		(fp_line
			(start -0.67945 -0.305054)
			(end -0.12065 -0.305054)
			(stroke
				(width 0.1)
				(type default)
			)
			(layer "F.Fab")
		)
		(fp_line
			(start 0.67945 -0.3048)
			(end 0.67945 0.3048)
			(stroke
				(width 0.1)
				(type default)
			)
			(layer "F.Fab")
		)
		(fp_line
			(start 0.12065 -0.3048)
			(end 0.67945 -0.3048)
			(stroke
				(width 0.1)
				(type default)
			)
			(layer "F.Fab")
		)
		(fp_line
			(start 0.12065 -0.2794)
			(end 0.12065 -0.3048)
			(stroke
				(width 0.1)
				(type default)
			)
			(layer "F.Fab")
		)
		(fp_line
			(start -0.12065 -0.2794)
			(end 0.12065 -0.2794)
			(stroke
				(width 0.1)
				(type default)
			)
			(layer "F.Fab")
		)
		(fp_line
			(start 0.120396 0.2794)
			(end -0.12065 0.2794)
			(stroke
				(width 0.1)
				(type default)
			)
			(layer "F.Fab")
		)
		(fp_line
			(start -0.12065 0.2794)
			(end -0.12065 0.3048)
			(stroke
				(width 0.1)
				(type default)
			)
			(layer "F.Fab")
		)
		(fp_line
			(start 0.67945 0.3048)
			(end 0.120396 0.3048)
			(stroke
				(width 0.1)
				(type default)
			)
			(layer "F.Fab")
		)
		(fp_line
			(start 0.120396 0.3048)
			(end 0.120396 0.2794)
			(stroke
				(width 0.1)
				(type default)
			)
			(layer "F.Fab")
		)
		(fp_line
			(start -0.12065 0.3048)
			(end -0.67945 0.3048)
			(stroke
				(width 0.1)
				(type default)
			)
			(layer "F.Fab")
		)
		(fp_line
			(start -0.67945 0.3048)
			(end -0.67945 -0.305054)
			(stroke
				(width 0.1)
				(type default)
			)
			(layer "F.Fab")
		)
		(pad "1" smd circle
			(at -0.40005 0 90)
			(size 0 0)
			(layers "F.Cu" "F.Mask" "F.Paste")
			(net "P3V3_NIC0_CO_DV_DT")
		)
		(pad "2" smd circle
			(at 0.40005 0 90)
			(size 0 0)
			(layers "F.Cu" "F.Mask" "F.Paste")
			(net "GND")
		)
	)
	(footprint ""
		(layer "F.Cu")
		(at 450.085968 -258.331208 -90)
		(property "Reference" "R6561"
			(at 0 0 270)
			(layer "F.SilkS")
			(hide yes)
			(effects
				(font
					(size 1.27 1.27)
				)
			)
		)
		(property "Value" ""
			(at 0 0 270)
			(layer "F.Fab")
			(effects
				(font
					(size 1.27 1.27)
				)
			)
		)
		(duplicate_pad_numbers_are_jumpers no)
		(fp_line
			(start -0.7874 0.4064)
			(end -0.7874 -0.4064)
			(stroke
				(width 0.1524)
				(type default)
			)
			(layer "F.SilkS")
		)
		(fp_line
			(start 0.7874 0.4064)
			(end -0.7874 0.4064)
			(stroke
				(width 0.1524)
				(type default)
			)
			(layer "F.SilkS")
		)
		(fp_line
			(start -0.7874 -0.4064)
			(end 0.7874 -0.4064)
			(stroke
				(width 0.1524)
				(type default)
			)
			(layer "F.SilkS")
		)
		(fp_line
			(start 0.7874 -0.4064)
			(end 0.7874 0.4064)
			(stroke
				(width 0.1524)
				(type default)
			)
			(layer "F.SilkS")
		)
		(fp_line
			(start -0.67945 0.3048)
			(end -0.67945 -0.305054)
			(stroke
				(width 0.1)
				(type default)
			)
			(layer "F.Fab")
		)
		(fp_line
			(start -0.12065 0.3048)
			(end -0.67945 0.3048)
			(stroke
				(width 0.1)
				(type default)
			)
			(layer "F.Fab")
		)
		(fp_line
			(start 0.120396 0.3048)
			(end 0.120396 0.2794)
			(stroke
				(width 0.1)
				(type default)
			)
			(layer "F.Fab")
		)
		(fp_line
			(start 0.67945 0.3048)
			(end 0.120396 0.3048)
			(stroke
				(width 0.1)
				(type default)
			)
			(layer "F.Fab")
		)
		(fp_line
			(start -0.12065 0.2794)
			(end -0.12065 0.3048)
			(stroke
				(width 0.1)
				(type default)
			)
			(layer "F.Fab")
		)
		(fp_line
			(start 0.120396 0.2794)
			(end -0.12065 0.2794)
			(stroke
				(width 0.1)
				(type default)
			)
			(layer "F.Fab")
		)
		(fp_line
			(start -0.12065 -0.2794)
			(end 0.12065 -0.2794)
			(stroke
				(width 0.1)
				(type default)
			)
			(layer "F.Fab")
		)
		(fp_line
			(start 0.12065 -0.2794)
			(end 0.12065 -0.3048)
			(stroke
				(width 0.1)
				(type default)
			)
			(layer "F.Fab")
		)
		(fp_line
			(start 0.12065 -0.3048)
			(end 0.67945 -0.3048)
			(stroke
				(width 0.1)
				(type default)
			)
			(layer "F.Fab")
		)
		(fp_line
			(start 0.67945 -0.3048)
			(end 0.67945 0.3048)
			(stroke
				(width 0.1)
				(type default)
			)
			(layer "F.Fab")
		)
		(fp_line
			(start -0.67945 -0.305054)
			(end -0.12065 -0.305054)
			(stroke
				(width 0.1)
				(type default)
			)
			(layer "F.Fab")
		)
		(fp_line
			(start -0.12065 -0.305054)
			(end -0.12065 -0.2794)
			(stroke
				(width 0.1)
				(type default)
			)
			(layer "F.Fab")
		)
		(pad "1" smd circle
			(at -0.40005 0 270)
			(size 0 0)
			(layers "F.Cu" "F.Mask" "F.Paste")
			(net "P1V25_SERDES_VDDPLL_PEX3")
		)
		(pad "2" smd circle
			(at 0.40005 0 270)
			(size 0 0)
			(layers "F.Cu" "F.Mask" "F.Paste")
			(net "P1V25_SERDES_VDDPLL_PEX3_C8")
		)
	)
)
